(kicad_pcb
	(version 20260206)
	(generator "pcbnew")
	(generator_version "10.0")
	(general
		(thickness 1.6)
		(legacy_teardrops no)
	)
	(paper "A4")
	(title_block
		(title "12092022_DA0F0TFB6D0_F0T_FAN_BOARD_MP5048_D_brd_v02_OCP.brd")
		(comment 1 "Grand Teton / footprints 381-386 of 924")
	)
	(layers
		(0 "F.Cu" signal "TOP")
		(4 "In1.Cu" signal "GND")
		(6 "In2.Cu" signal "IN1")
		(8 "In3.Cu" signal "IN2")
		(10 "In4.Cu" signal "GND1")
		(2 "B.Cu" signal "BOTTOM")
		(9 "F.Adhes" user "F.Adhesive")
		(11 "B.Adhes" user "B.Adhesive")
		(13 "F.Paste" user "Package Geometry/Pastemask Top")
		(15 "B.Paste" user "Package Geometry/Pastemask Bottom")
		(5 "F.SilkS" user "Ref Des/Silkscreen Top")
		(7 "B.SilkS" user "Ref Des/Silkscreen Bottom")
		(1 "F.Mask" user "Board Geometry/Soldermask Top")
		(3 "B.Mask" user "Board Geometry/Soldermask Bottom")
		(17 "Dwgs.User" user "User.Drawings")
		(19 "Cmts.User" user "User.Comments")
		(21 "Eco1.User" user "User.Eco1")
		(23 "Eco2.User" user "User.Eco2")
		(25 "Edge.Cuts" user "Board Geometry/Outline")
		(27 "Margin" user)
		(31 "F.CrtYd" user "Package Geometry/Place Bound Top")
		(29 "B.CrtYd" user "Package Geometry/Place Bound Bottom")
		(35 "F.Fab" user "Ref Des/Assembly Top")
		(33 "B.Fab" user "Ref Des/Assembly Bottom")
	)
	(footprint ""
		(layer "F.Cu")
		(at 19.558 -207.01 -90)
		(property "Reference" "R5371"
			(at 0 0 270)
			(layer "F.SilkS")
			(hide yes)
			(effects
				(font
					(size 1.27 1.27)
				)
			)
		)
		(property "Value" ""
			(at 0 0 270)
			(layer "F.Fab")
			(effects
				(font
					(size 1.27 1.27)
				)
			)
		)
		(duplicate_pad_numbers_are_jumpers no)
		(fp_line
			(start -0.7874 0.4064)
			(end -0.7874 -0.4064)
			(stroke
				(width 0.1524)
				(type default)
			)
			(layer "F.SilkS")
		)
		(fp_line
			(start 0.7874 0.4064)
			(end -0.7874 0.4064)
			(stroke
				(width 0.1524)
				(type default)
			)
			(layer "F.SilkS")
		)
		(fp_line
			(start -0.7874 -0.4064)
			(end 0.7874 -0.4064)
			(stroke
				(width 0.1524)
				(type default)
			)
			(layer "F.SilkS")
		)
		(fp_line
			(start 0.7874 -0.4064)
			(end 0.7874 0.4064)
			(stroke
				(width 0.1524)
				(type default)
			)
			(layer "F.SilkS")
		)
		(fp_line
			(start -0.67945 0.3048)
			(end -0.67945 -0.305054)
			(stroke
				(width 0.1)
				(type default)
			)
			(layer "F.Fab")
		)
		(fp_line
			(start -0.12065 0.3048)
			(end -0.67945 0.3048)
			(stroke
				(width 0.1)
				(type default)
			)
			(layer "F.Fab")
		)
		(fp_line
			(start 0.120396 0.3048)
			(end 0.120396 0.2794)
			(stroke
				(width 0.1)
				(type default)
			)
			(layer "F.Fab")
		)
		(fp_line
			(start 0.67945 0.3048)
			(end 0.120396 0.3048)
			(stroke
				(width 0.1)
				(type default)
			)
			(layer "F.Fab")
		)
		(fp_line
			(start -0.12065 0.2794)
			(end -0.12065 0.3048)
			(stroke
				(width 0.1)
				(type default)
			)
			(layer "F.Fab")
		)
		(fp_line
			(start 0.120396 0.2794)
			(end -0.12065 0.2794)
			(stroke
				(width 0.1)
				(type default)
			)
			(layer "F.Fab")
		)
		(fp_line
			(start -0.12065 -0.2794)
			(end 0.12065 -0.2794)
			(stroke
				(width 0.1)
				(type default)
			)
			(layer "F.Fab")
		)
		(fp_line
			(start 0.12065 -0.2794)
			(end 0.12065 -0.3048)
			(stroke
				(width 0.1)
				(type default)
			)
			(layer "F.Fab")
		)
		(fp_line
			(start 0.12065 -0.3048)
			(end 0.67945 -0.3048)
			(stroke
				(width 0.1)
				(type default)
			)
			(layer "F.Fab")
		)
		(fp_line
			(start 0.67945 -0.3048)
			(end 0.67945 0.3048)
			(stroke
				(width 0.1)
				(type default)
			)
			(layer "F.Fab")
		)
		(fp_line
			(start -0.67945 -0.305054)
			(end -0.12065 -0.305054)
			(stroke
				(width 0.1)
				(type default)
			)
			(layer "F.Fab")
		)
		(fp_line
			(start -0.12065 -0.305054)
			(end -0.12065 -0.2794)
			(stroke
				(width 0.1)
				(type default)
			)
			(layer "F.Fab")
		)
		(pad "1" smd circle
			(at -0.40005 0 270)
			(size 0 0)
			(layers "F.Cu" "F.Mask" "F.Paste")
			(net "P3V3_AUX")
		)
		(pad "2" smd circle
			(at 0.40005 0 270)
			(size 0 0)
			(layers "F.Cu" "F.Mask" "F.Paste")
			(net "FAN_6_OK_R_LED")
		)
	)
	(footprint ""
		(layer "F.Cu")
		(at 25.527 -127.889)
		(property "Reference" "R4949"
			(at 0 0 0)
			(layer "F.SilkS")
			(hide yes)
			(effects
				(font
					(size 1.27 1.27)
				)
			)
		)
		(property "Value" ""
			(at 0 0 0)
			(layer "F.Fab")
			(effects
				(font
					(size 1.27 1.27)
				)
			)
		)
		(duplicate_pad_numbers_are_jumpers no)
		(fp_line
			(start -0.7874 -0.4064)
			(end 0.7874 -0.4064)
			(stroke
				(width 0.1524)
				(type default)
			)
			(layer "F.SilkS")
		)
		(fp_line
			(start -0.7874 0.4064)
			(end -0.7874 -0.4064)
			(stroke
				(width 0.1524)
				(type default)
			)
			(layer "F.SilkS")
		)
		(fp_line
			(start 0.7874 -0.4064)
			(end 0.7874 0.4064)
			(stroke
				(width 0.1524)
				(type default)
			)
			(layer "F.SilkS")
		)
		(fp_line
			(start 0.7874 0.4064)
			(end -0.7874 0.4064)
			(stroke
				(width 0.1524)
				(type default)
			)
			(layer "F.SilkS")
		)
		(fp_line
			(start -0.67945 -0.305054)
			(end -0.12065 -0.305054)
			(stroke
				(width 0.1)
				(type default)
			)
			(layer "F.Fab")
		)
		(fp_line
			(start -0.67945 0.3048)
			(end -0.67945 -0.305054)
			(stroke
				(width 0.1)
				(type default)
			)
			(layer "F.Fab")
		)
		(fp_line
			(start -0.12065 -0.305054)
			(end -0.12065 -0.2794)
			(stroke
				(width 0.1)
				(type default)
			)
			(layer "F.Fab")
		)
		(fp_line
			(start -0.12065 -0.2794)
			(end 0.12065 -0.2794)
			(stroke
				(width 0.1)
				(type default)
			)
			(layer "F.Fab")
		)
		(fp_line
			(start -0.12065 0.2794)
			(end -0.12065 0.3048)
			(stroke
				(width 0.1)
				(type default)
			)
			(layer "F.Fab")
		)
		(fp_line
			(start -0.12065 0.3048)
			(end -0.67945 0.3048)
			(stroke
				(width 0.1)
				(type default)
			)
			(layer "F.Fab")
		)
		(fp_line
			(start 0.120396 0.2794)
			(end -0.12065 0.2794)
			(stroke
				(width 0.1)
				(type default)
			)
			(layer "F.Fab")
		)
		(fp_line
			(start 0.120396 0.3048)
			(end 0.120396 0.2794)
			(stroke
				(width 0.1)
				(type default)
			)
			(layer "F.Fab")
		)
		(fp_line
			(start 0.12065 -0.3048)
			(end 0.67945 -0.3048)
			(stroke
				(width 0.1)
				(type default)
			)
			(layer "F.Fab")
		)
		(fp_line
			(start 0.12065 -0.2794)
			(end 0.12065 -0.3048)
			(stroke
				(width 0.1)
				(type default)
			)
			(layer "F.Fab")
		)
		(fp_line
			(start 0.67945 -0.3048)
			(end 0.67945 0.3048)
			(stroke
				(width 0.1)
				(type default)
			)
			(layer "F.Fab")
		)
		(fp_line
			(start 0.67945 0.3048)
			(end 0.120396 0.3048)
			(stroke
				(width 0.1)
				(type default)
			)
			(layer "F.Fab")
		)
		(pad "1" smd circle
			(at -0.40005 0)
			(size 0 0)
			(layers "F.Cu" "F.Mask" "F.Paste")
			(net "MAX31790_U330_PWM_START1")
		)
		(pad "2" smd circle
			(at 0.40005 0)
			(size 0 0)
			(layers "F.Cu" "F.Mask" "F.Paste")
			(net "P3V3_AUX")
		)
	)
	(footprint ""
		(layer "F.Cu")
		(at 14.351 -116.135912 180)
		(property "Reference" "D246"
			(at 4.445 2.582418 0)
			(unlocked yes)
			(layer "F.SilkS")
			(effects
				(font
					(size 0.7874 0.5842)
					(thickness 0.1524)
				)
				(justify left)
			)
		)
		(property "Value" ""
			(at 0 0 180)
			(layer "F.Fab")
			(effects
				(font
					(size 1.27 1.27)
				)
			)
		)
		(duplicate_pad_numbers_are_jumpers no)
		(fp_line
			(start 0.94488 0.450088)
			(end 0.94488 -0.450088)
			(stroke
				(width 0.1524)
				(type default)
			)
			(layer "F.SilkS")
		)
		(fp_line
			(start 0.94488 -0.450088)
			(end -0.854964 -0.450088)
			(stroke
				(width 0.1524)
				(type default)
			)
			(layer "F.SilkS")
		)
		(fp_line
			(start 0.870458 -0.2794)
			(end 0.845058 0.4064)
			(stroke
				(width 0.1524)
				(type default)
			)
			(layer "F.SilkS")
		)
		(fp_line
			(start 0.845058 0.4064)
			(end 0.845058 -0.381)
			(stroke
				(width 0.1524)
				(type default)
			)
			(layer "F.SilkS")
		)
		(fp_line
			(start -0.854964 0.450088)
			(end 0.925068 0.450088)
			(stroke
				(width 0.1524)
				(type default)
			)
			(layer "F.SilkS")
		)
		(fp_line
			(start -0.854964 -0.450088)
			(end -0.854964 0.450088)
			(stroke
				(width 0.1524)
				(type default)
			)
			(layer "F.SilkS")
		)
		(fp_line
			(start 0.54991 0.350012)
			(end 0.54991 -0.350012)
			(stroke
				(width 0.1)
				(type default)
			)
			(layer "F.Fab")
		)
		(fp_line
			(start 0.54991 -0.350012)
			(end -0.54991 -0.350012)
			(stroke
				(width 0.1)
				(type default)
			)
			(layer "F.Fab")
		)
		(fp_line
			(start -0.54991 0.350012)
			(end 0.54991 0.350012)
			(stroke
				(width 0.1)
				(type default)
			)
			(layer "F.Fab")
		)
		(fp_line
			(start -0.54991 -0.350012)
			(end -0.54991 0.350012)
			(stroke
				(width 0.1)
				(type default)
			)
			(layer "F.Fab")
		)
		(fp_text user "-"
			(at 2.286 -0.470662 0)
			(unlocked yes)
			(layer "F.SilkS")
			(effects
				(font
					(size 1.905 1.4224)
					(thickness 0.1524)
				)
				(justify left)
			)
		)
		(fp_text user "+"
			(at -0.635 0.291338 0)
			(unlocked yes)
			(layer "F.SilkS")
			(effects
				(font
					(size 1.905 1.4224)
					(thickness 0.1524)
				)
				(justify left)
			)
		)
		(fp_text user "-"
			(at 2.48539 0.239014 0)
			(unlocked yes)
			(layer "F.Fab")
			(effects
				(font
					(size 1.905 1.4224)
					(thickness 0.1524)
				)
				(justify left)
			)
		)
		(fp_text user "+"
			(at -0.808228 0.239014 0)
			(unlocked yes)
			(layer "F.Fab")
			(effects
				(font
					(size 1.905 1.4224)
					(thickness 0.1524)
				)
				(justify left)
			)
		)
		(pad "A" smd rect
			(at -0.424942 0 180)
			(size 0.5588 0.6096)
			(layers "F.Cu" "F.Mask" "F.Paste")
			(net "GND")
		)
		(pad "C" smd rect
			(at 0.424942 0)
			(size 0.5588 0.6096)
			(layers "F.Cu" "F.Mask" "F.Paste")
			(net "FAN_5_OK_R_LED_N")
		)
	)
	(footprint ""
		(layer "F.Cu")
		(at 39.243 -73.66 90)
		(property "Reference" "PR37"
			(at 0 0 90)
			(layer "F.SilkS")
			(hide yes)
			(effects
				(font
					(size 1.27 1.27)
				)
			)
		)
		(property "Value" ""
			(at 0 0 90)
			(layer "F.Fab")
			(effects
				(font
					(size 1.27 1.27)
				)
			)
		)
		(duplicate_pad_numbers_are_jumpers no)
		(fp_line
			(start 0.7874 -0.4064)
			(end 0.7874 0.4064)
			(stroke
				(width 0.1524)
				(type default)
			)
			(layer "F.SilkS")
		)
		(fp_line
			(start -0.7874 -0.4064)
			(end 0.7874 -0.4064)
			(stroke
				(width 0.1524)
				(type default)
			)
			(layer "F.SilkS")
		)
		(fp_line
			(start 0.7874 0.4064)
			(end -0.7874 0.4064)
			(stroke
				(width 0.1524)
				(type default)
			)
			(layer "F.SilkS")
		)
		(fp_line
			(start -0.7874 0.4064)
			(end -0.7874 -0.4064)
			(stroke
				(width 0.1524)
				(type default)
			)
			(layer "F.SilkS")
		)
		(fp_line
			(start -0.12065 -0.305054)
			(end -0.12065 -0.2794)
			(stroke
				(width 0.1)
				(type default)
			)
			(layer "F.Fab")
		)
		(fp_line
			(start -0.67945 -0.305054)
			(end -0.12065 -0.305054)
			(stroke
				(width 0.1)
				(type default)
			)
			(layer "F.Fab")
		)
		(fp_line
			(start 0.67945 -0.3048)
			(end 0.67945 0.3048)
			(stroke
				(width 0.1)
				(type default)
			)
			(layer "F.Fab")
		)
		(fp_line
			(start 0.12065 -0.3048)
			(end 0.67945 -0.3048)
			(stroke
				(width 0.1)
				(type default)
			)
			(layer "F.Fab")
		)
		(fp_line
			(start 0.12065 -0.2794)
			(end 0.12065 -0.3048)
			(stroke
				(width 0.1)
				(type default)
			)
			(layer "F.Fab")
		)
		(fp_line
			(start -0.12065 -0.2794)
			(end 0.12065 -0.2794)
			(stroke
				(width 0.1)
				(type default)
			)
			(layer "F.Fab")
		)
		(fp_line
			(start 0.120396 0.2794)
			(end -0.12065 0.2794)
			(stroke
				(width 0.1)
				(type default)
			)
			(layer "F.Fab")
		)
		(fp_line
			(start -0.12065 0.2794)
			(end -0.12065 0.3048)
			(stroke
				(width 0.1)
				(type default)
			)
			(layer "F.Fab")
		)
		(fp_line
			(start 0.67945 0.3048)
			(end 0.120396 0.3048)
			(stroke
				(width 0.1)
				(type default)
			)
			(layer "F.Fab")
		)
		(fp_line
			(start 0.120396 0.3048)
			(end 0.120396 0.2794)
			(stroke
				(width 0.1)
				(type default)
			)
			(layer "F.Fab")
		)
		(fp_line
			(start -0.12065 0.3048)
			(end -0.67945 0.3048)
			(stroke
				(width 0.1)
				(type default)
			)
			(layer "F.Fab")
		)
		(fp_line
			(start -0.67945 0.3048)
			(end -0.67945 -0.305054)
			(stroke
				(width 0.1)
				(type default)
			)
			(layer "F.Fab")
		)
		(pad "1" smd circle
			(at -0.40005 0 90)
			(size 0 0)
			(layers "F.Cu" "F.Mask" "F.Paste")
			(net "FAN_2_P3V_R")
		)
		(pad "2" smd circle
			(at 0.40005 0 90)
			(size 0 0)
			(layers "F.Cu" "F.Mask" "F.Paste")
			(net "FAN_2_MODE")
		)
	)
	(footprint ""
		(layer "F.Cu")
		(at 37.465 -119.564912)
		(property "Reference" "R5216"
			(at 0 0 0)
			(layer "F.SilkS")
			(hide yes)
			(effects
				(font
					(size 1.27 1.27)
				)
			)
		)
		(property "Value" ""
			(at 0 0 0)
			(layer "F.Fab")
			(effects
				(font
					(size 1.27 1.27)
				)
			)
		)
		(duplicate_pad_numbers_are_jumpers no)
		(fp_line
			(start -0.7874 -0.4064)
			(end 0.7874 -0.4064)
			(stroke
				(width 0.1524)
				(type default)
			)
			(layer "F.SilkS")
		)
		(fp_line
			(start -0.7874 0.4064)
			(end -0.7874 -0.4064)
			(stroke
				(width 0.1524)
				(type default)
			)
			(layer "F.SilkS")
		)
		(fp_line
			(start 0.7874 -0.4064)
			(end 0.7874 0.4064)
			(stroke
				(width 0.1524)
				(type default)
			)
			(layer "F.SilkS")
		)
		(fp_line
			(start 0.7874 0.4064)
			(end -0.7874 0.4064)
			(stroke
				(width 0.1524)
				(type default)
			)
			(layer "F.SilkS")
		)
		(fp_line
			(start -0.67945 -0.305054)
			(end -0.12065 -0.305054)
			(stroke
				(width 0.1)
				(type default)
			)
			(layer "F.Fab")
		)
		(fp_line
			(start -0.67945 0.3048)
			(end -0.67945 -0.305054)
			(stroke
				(width 0.1)
				(type default)
			)
			(layer "F.Fab")
		)
		(fp_line
			(start -0.12065 -0.305054)
			(end -0.12065 -0.2794)
			(stroke
				(width 0.1)
				(type default)
			)
			(layer "F.Fab")
		)
		(fp_line
			(start -0.12065 -0.2794)
			(end 0.12065 -0.2794)
			(stroke
				(width 0.1)
				(type default)
			)
			(layer "F.Fab")
		)
		(fp_line
			(start -0.12065 0.2794)
			(end -0.12065 0.3048)
			(stroke
				(width 0.1)
				(type default)
			)
			(layer "F.Fab")
		)
		(fp_line
			(start -0.12065 0.3048)
			(end -0.67945 0.3048)
			(stroke
				(width 0.1)
				(type default)
			)
			(layer "F.Fab")
		)
		(fp_line
			(start 0.120396 0.2794)
			(end -0.12065 0.2794)
			(stroke
				(width 0.1)
				(type default)
			)
			(layer "F.Fab")
		)
		(fp_line
			(start 0.120396 0.3048)
			(end 0.120396 0.2794)
			(stroke
				(width 0.1)
				(type default)
			)
			(layer "F.Fab")
		)
		(fp_line
			(start 0.12065 -0.3048)
			(end 0.67945 -0.3048)
			(stroke
				(width 0.1)
				(type default)
			)
			(layer "F.Fab")
		)
		(fp_line
			(start 0.12065 -0.2794)
			(end 0.12065 -0.3048)
			(stroke
				(width 0.1)
				(type default)
			)
			(layer "F.Fab")
		)
		(fp_line
			(start 0.67945 -0.3048)
			(end 0.67945 0.3048)
			(stroke
				(width 0.1)
				(type default)
			)
			(layer "F.Fab")
		)
		(fp_line
			(start 0.67945 0.3048)
			(end 0.120396 0.3048)
			(stroke
				(width 0.1)
				(type default)
			)
			(layer "F.Fab")
		)
		(pad "1" smd circle
			(at -0.40005 0)
			(size 0 0)
			(layers "F.Cu" "F.Mask" "F.Paste")
			(net "FAN_2_PWM_OL")
		)
		(pad "2" smd circle
			(at 0.40005 0)
			(size 0 0)
			(layers "F.Cu" "F.Mask" "F.Paste")
			(net "FAN_2_PWM_OL_R")
		)
	)
	(footprint ""
		(layer "F.Cu")
		(at 18.415 -189.611)
		(property "Reference" "R309"
			(at 0 0 0)
			(layer "F.SilkS")
			(hide yes)
			(effects
				(font
					(size 1.27 1.27)
				)
			)
		)
		(property "Value" ""
			(at 0 0 0)
			(layer "F.Fab")
			(effects
				(font
					(size 1.27 1.27)
				)
			)
		)
		(duplicate_pad_numbers_are_jumpers no)
		(fp_line
			(start -0.7874 -0.4064)
			(end 0.7874 -0.4064)
			(stroke
				(width 0.1524)
				(type default)
			)
			(layer "F.SilkS")
		)
		(fp_line
			(start -0.7874 0.4064)
			(end -0.7874 -0.4064)
			(stroke
				(width 0.1524)
				(type default)
			)
			(layer "F.SilkS")
		)
		(fp_line
			(start 0.7874 -0.4064)
			(end 0.7874 0.4064)
			(stroke
				(width 0.1524)
				(type default)
			)
			(layer "F.SilkS")
		)
		(fp_line
			(start 0.7874 0.4064)
			(end -0.7874 0.4064)
			(stroke
				(width 0.1524)
				(type default)
			)
			(layer "F.SilkS")
		)
		(fp_line
			(start -0.67945 -0.305054)
			(end -0.12065 -0.305054)
			(stroke
				(width 0.1)
				(type default)
			)
			(layer "F.Fab")
		)
		(fp_line
			(start -0.67945 0.3048)
			(end -0.67945 -0.305054)
			(stroke
				(width 0.1)
				(type default)
			)
			(layer "F.Fab")
		)
		(fp_line
			(start -0.12065 -0.305054)
			(end -0.12065 -0.2794)
			(stroke
				(width 0.1)
				(type default)
			)
			(layer "F.Fab")
		)
		(fp_line
			(start -0.12065 -0.2794)
			(end 0.12065 -0.2794)
			(stroke
				(width 0.1)
				(type default)
			)
			(layer "F.Fab")
		)
		(fp_line
			(start -0.12065 0.2794)
			(end -0.12065 0.3048)
			(stroke
				(width 0.1)
				(type default)
			)
			(layer "F.Fab")
		)
		(fp_line
			(start -0.12065 0.3048)
			(end -0.67945 0.3048)
			(stroke
				(width 0.1)
				(type default)
			)
			(layer "F.Fab")
		)
		(fp_line
			(start 0.120396 0.2794)
			(end -0.12065 0.2794)
			(stroke
				(width 0.1)
				(type default)
			)
			(layer "F.Fab")
		)
		(fp_line
			(start 0.120396 0.3048)
			(end 0.120396 0.2794)
			(stroke
				(width 0.1)
				(type default)
			)
			(layer "F.Fab")
		)
		(fp_line
			(start 0.12065 -0.3048)
			(end 0.67945 -0.3048)
			(stroke
				(width 0.1)
				(type default)
			)
			(layer "F.Fab")
		)
		(fp_line
			(start 0.12065 -0.2794)
			(end 0.12065 -0.3048)
			(stroke
				(width 0.1)
				(type default)
			)
			(layer "F.Fab")
		)
		(fp_line
			(start 0.67945 -0.3048)
			(end 0.67945 0.3048)
			(stroke
				(width 0.1)
				(type default)
			)
			(layer "F.Fab")
		)
		(fp_line
			(start 0.67945 0.3048)
			(end 0.120396 0.3048)
			(stroke
				(width 0.1)
				(type default)
			)
			(layer "F.Fab")
		)
		(pad "1" smd rect
			(at -0.40005 0 180)
			(size 0.4572 0.508)
			(layers "F.Cu" "F.Mask" "F.Paste")
			(net "FRU_WP_N")
		)
		(pad "2" smd rect
			(at 0.40005 0 180)
			(size 0.4572 0.508)
			(layers "F.Cu" "F.Mask" "F.Paste")
			(net "GND")
		)
	)
)
